(kicad_pcb
	(version 20260206)
	(generator "pcbnew")
	(generator_version "10.0")
	(general
		(thickness 1.6)
		(legacy_teardrops no)
	)
	(paper "A4")
	(title_block
		(title "Wiwynn_Tioga_Pass_MB.brd")
		(comment 1 "Tioga Pass / footprints 3667-3674 of 4770")
	)
	(layers
		(0 "F.Cu" signal "TOP")
		(4 "In1.Cu" signal "L2GND")
		(6 "In2.Cu" signal "L3")
		(8 "In3.Cu" signal "L4GND")
		(10 "In4.Cu" signal "L5")
		(12 "In5.Cu" signal "L6GND")
		(14 "In6.Cu" signal "L7VCC")
		(16 "In7.Cu" signal "L8VCC")
		(18 "In8.Cu" signal "L9GND")
		(20 "In9.Cu" signal "L10")
		(22 "In10.Cu" signal "L11GND")
		(24 "In11.Cu" signal "L12")
		(26 "In12.Cu" signal "L13GND")
		(2 "B.Cu" signal "BOTTOM")
		(9 "F.Adhes" user "F.Adhesive")
		(11 "B.Adhes" user "B.Adhesive")
		(13 "F.Paste" user "Package Geometry/Pastemask Top")
		(15 "B.Paste" user "Package Geometry/Pastemask Bottom")
		(5 "F.SilkS" user "Ref Des/Silkscreen Top")
		(7 "B.SilkS" user "Ref Des/Silkscreen Bottom")
		(1 "F.Mask" user "Board Geometry/Soldermask Top")
		(3 "B.Mask" user "Board Geometry/Soldermask Bottom")
		(17 "Dwgs.User" user "User.Drawings")
		(19 "Cmts.User" user "User.Comments")
		(21 "Eco1.User" user "User.Eco1")
		(23 "Eco2.User" user "User.Eco2")
		(25 "Edge.Cuts" user "Board Geometry/Outline")
		(27 "Margin" user)
		(31 "F.CrtYd" user "Package Geometry/Place Bound Top")
		(29 "B.CrtYd" user "Package Geometry/Place Bound Bottom")
		(35 "F.Fab" user "Ref Des/Assembly Top")
		(33 "B.Fab" user "Ref Des/Assembly Bottom")
	)
	(footprint ""
		(layer "B.Cu")
		(at 106.350054 -73.51014)
		(property "Reference" "C8P22"
			(at 0 0 0)
			(layer "B.SilkS")
			(hide yes)
			(effects
				(font
					(size 1.27 1.27)
				)
				(justify mirror)
			)
		)
		(property "Value" ""
			(at 0 0 0)
			(layer "B.Fab")
			(effects
				(font
					(size 1.27 1.27)
				)
				(justify mirror)
			)
		)
		(duplicate_pad_numbers_are_jumpers no)
		(fp_poly
			(pts
				(xy 0.7239 -0.2159) (xy -0.7239 -0.2159) (xy -0.7239 1.9939) (xy 0.7239 1.9939)
			)
			(stroke
				(width 0)
				(type default)
			)
			(fill no)
			(layer "B.CrtYd")
		)
		(fp_line
			(start -0.7239 -0.2159)
			(end 0.7239 -0.2159)
			(stroke
				(width 0.1)
				(type default)
			)
			(layer "B.Fab")
		)
		(fp_line
			(start -0.7239 1.9939)
			(end -0.7239 -0.2159)
			(stroke
				(width 0.1)
				(type default)
			)
			(layer "B.Fab")
		)
		(fp_line
			(start 0.7239 -0.2159)
			(end 0.7239 1.9939)
			(stroke
				(width 0.1)
				(type default)
			)
			(layer "B.Fab")
		)
		(fp_line
			(start 0.7239 1.9939)
			(end -0.7239 1.9939)
			(stroke
				(width 0.1)
				(type default)
			)
			(layer "B.Fab")
		)
		(pad "1" smd rect
			(at 0 0 180)
			(size 1.27 1.016)
			(layers "B.Cu" "B.Mask" "B.Paste")
			(net "PVCCMCP_CPU1")
		)
		(pad "2" smd rect
			(at 0 1.778 180)
			(size 1.27 1.016)
			(layers "B.Cu" "B.Mask" "B.Paste")
			(net "GND")
		)
		(zone
			(layer "B.Cu")
			(hatch none 0.5)
			(connect_pads
				(clearance 0)
			)
			(min_thickness 0.25)
			(keepout
				(tracks not_allowed)
				(vias allowed)
				(pads allowed)
				(copperpour not_allowed)
				(footprints allowed)
			)
			(placement
				(enabled no)
				(sheetname "")
			)
			(fill
				(thermal_gap 0.5)
				(thermal_bridge_width 0.5)
				(island_removal_mode 0)
			)
			(polygon
				(pts
					(xy 106.985054 -73.00214) (xy 105.715054 -73.00214) (xy 105.715054 -72.24014) (xy 106.985054 -72.24014)
				)
			)
		)
	)
	(footprint ""
		(layer "B.Cu")
		(at 463.690208 -145.415254)
		(property "Reference" "C1L8"
			(at 0 0 0)
			(layer "B.SilkS")
			(hide yes)
			(effects
				(font
					(size 1.27 1.27)
				)
				(justify mirror)
			)
		)
		(property "Value" ""
			(at 0 0 0)
			(layer "B.Fab")
			(effects
				(font
					(size 1.27 1.27)
				)
				(justify mirror)
			)
		)
		(duplicate_pad_numbers_are_jumpers no)
		(fp_poly
			(pts
				(xy -0.3048 -0.1016) (xy -0.3048 0.9906) (xy 0.3048 0.9906) (xy 0.3048 -0.1016)
			)
			(stroke
				(width 0)
				(type default)
			)
			(fill no)
			(layer "B.CrtYd")
		)
		(fp_line
			(start -0.3048 -0.1016)
			(end 0.3048 -0.1016)
			(stroke
				(width 0.1)
				(type default)
			)
			(layer "B.Fab")
		)
		(fp_line
			(start -0.3048 0.9906)
			(end -0.3048 -0.1016)
			(stroke
				(width 0.1)
				(type default)
			)
			(layer "B.Fab")
		)
		(fp_line
			(start 0.3048 -0.1016)
			(end 0.3048 0.9906)
			(stroke
				(width 0.1)
				(type default)
			)
			(layer "B.Fab")
		)
		(fp_line
			(start 0.3048 0.9906)
			(end -0.3048 0.9906)
			(stroke
				(width 0.1)
				(type default)
			)
			(layer "B.Fab")
		)
		(pad "1" smd rect
			(at 0 0 180)
			(size 0.508 0.508)
			(layers "B.Cu" "B.Mask" "B.Paste")
			(net "XDP_PWRGD_RST_N")
		)
		(pad "2" smd rect
			(at 0 0.889 180)
			(size 0.508 0.508)
			(layers "B.Cu" "B.Mask" "B.Paste")
			(net "GND")
		)
		(zone
			(layer "B.Cu")
			(hatch none 0.5)
			(connect_pads
				(clearance 0)
			)
			(min_thickness 0.25)
			(keepout
				(tracks allowed)
				(vias not_allowed)
				(pads allowed)
				(copperpour not_allowed)
				(footprints allowed)
			)
			(placement
				(enabled no)
				(sheetname "")
			)
			(fill
				(thermal_gap 0.5)
				(thermal_bridge_width 0.5)
				(island_removal_mode 0)
			)
			(polygon
				(pts
					(xy 463.944208 -145.161254) (xy 463.436208 -145.161254) (xy 463.436208 -144.780254) (xy 463.944208 -144.780254)
				)
			)
		)
		(zone
			(layer "B.Cu")
			(hatch none 0.5)
			(connect_pads
				(clearance 0)
			)
			(min_thickness 0.25)
			(keepout
				(tracks not_allowed)
				(vias allowed)
				(pads allowed)
				(copperpour not_allowed)
				(footprints allowed)
			)
			(placement
				(enabled no)
				(sheetname "")
			)
			(fill
				(thermal_gap 0.5)
				(thermal_bridge_width 0.5)
				(island_removal_mode 0)
			)
			(polygon
				(pts
					(xy 463.944208 -144.780254) (xy 463.436208 -144.780254) (xy 463.436208 -145.161254) (xy 463.944208 -145.161254)
				)
			)
		)
	)
	(footprint ""
		(layer "B.Cu")
		(at 479.8695 -33.147 -90)
		(property "Reference" "C2T34"
			(at 0 0 90)
			(layer "B.SilkS")
			(hide yes)
			(effects
				(font
					(size 1.27 1.27)
				)
				(justify mirror)
			)
		)
		(property "Value" ""
			(at 0 0 90)
			(layer "B.Fab")
			(effects
				(font
					(size 1.27 1.27)
				)
				(justify mirror)
			)
		)
		(duplicate_pad_numbers_are_jumpers no)
		(fp_poly
			(pts
				(xy -0.3048 -0.1016) (xy -0.3048 0.9906) (xy 0.3048 0.9906) (xy 0.3048 -0.1016)
			)
			(stroke
				(width 0)
				(type default)
			)
			(fill no)
			(layer "B.CrtYd")
		)
		(fp_line
			(start -0.3048 0.9906)
			(end -0.3048 -0.1016)
			(stroke
				(width 0.1)
				(type default)
			)
			(layer "B.Fab")
		)
		(fp_line
			(start 0.3048 0.9906)
			(end -0.3048 0.9906)
			(stroke
				(width 0.1)
				(type default)
			)
			(layer "B.Fab")
		)
		(fp_line
			(start -0.3048 -0.1016)
			(end 0.3048 -0.1016)
			(stroke
				(width 0.1)
				(type default)
			)
			(layer "B.Fab")
		)
		(fp_line
			(start 0.3048 -0.1016)
			(end 0.3048 0.9906)
			(stroke
				(width 0.1)
				(type default)
			)
			(layer "B.Fab")
		)
		(pad "1" smd rect
			(at 0 0 90)
			(size 0.508 0.508)
			(layers "B.Cu" "B.Mask" "B.Paste")
			(net "P3V3_STBY_MNG")
		)
		(pad "2" smd rect
			(at 0 0.889 90)
			(size 0.508 0.508)
			(layers "B.Cu" "B.Mask" "B.Paste")
			(net "GND")
		)
		(zone
			(layer "B.Cu")
			(hatch none 0.5)
			(connect_pads
				(clearance 0)
			)
			(min_thickness 0.25)
			(keepout
				(tracks not_allowed)
				(vias allowed)
				(pads allowed)
				(copperpour not_allowed)
				(footprints allowed)
			)
			(placement
				(enabled no)
				(sheetname "")
			)
			(fill
				(thermal_gap 0.5)
				(thermal_bridge_width 0.5)
				(island_removal_mode 0)
			)
			(polygon
				(pts
					(xy 479.2345 -32.893) (xy 479.2345 -33.401) (xy 479.6155 -33.401) (xy 479.6155 -32.893)
				)
			)
		)
		(zone
			(layer "B.Cu")
			(hatch none 0.5)
			(connect_pads
				(clearance 0)
			)
			(min_thickness 0.25)
			(keepout
				(tracks allowed)
				(vias not_allowed)
				(pads allowed)
				(copperpour not_allowed)
				(footprints allowed)
			)
			(placement
				(enabled no)
				(sheetname "")
			)
			(fill
				(thermal_gap 0.5)
				(thermal_bridge_width 0.5)
				(island_removal_mode 0)
			)
			(polygon
				(pts
					(xy 479.6155 -32.893) (xy 479.6155 -33.401) (xy 479.2345 -33.401) (xy 479.2345 -32.893)
				)
			)
		)
	)
	(footprint ""
		(layer "B.Cu")
		(at 452.857362 -17.749266 -90)
		(property "Reference" "C8W1"
			(at 0 0 90)
			(layer "B.SilkS")
			(hide yes)
			(effects
				(font
					(size 1.27 1.27)
				)
				(justify mirror)
			)
		)
		(property "Value" "*"
			(at 0 -2.9337 270)
			(unlocked yes)
			(layer "B.Fab")
			(hide yes)
			(effects
				(font
					(size 1.27 1.016)
					(thickness 0.1524)
				)
				(justify mirror)
			)
		)
		(property "Device Type" "SC1U16V3KX-2GP_SMD-BCG-SC1U16VA"
			(at 0 -4.4577 270)
			(unlocked yes)
			(layer "B.Fab")
			(hide yes)
			(effects
				(font
					(size 1.27 1.016)
					(thickness 0.1524)
				)
				(justify mirror)
			)
		)
		(duplicate_pad_numbers_are_jumpers no)
		(fp_line
			(start -0.508 0)
			(end 0.508 0)
			(stroke
				(width 0.2032)
				(type default)
			)
			(layer "B.SilkS")
		)
		(fp_rect
			(start 0.5842 1.3335)
			(end -0.5842 -1.3335)
			(stroke
				(width 0)
				(type default)
			)
			(fill no)
			(layer "B.CrtYd")
		)
		(fp_rect
			(start 0.5842 1.3335)
			(end -0.5842 -1.3335)
			(stroke
				(width 0)
				(type default)
			)
			(fill no)
			(layer "B.Fab")
		)
		(pad "1" smd custom
			(at 0 -0.762 90)
			(size 0.2159 0.2159)
			(layers "B.Cu" "B.Mask" "B.Paste")
			(net "BMC_SELF_HW_D_RST")
			(options
				(clearance outline)
				(anchor circle)
			)
			(primitives
				(gr_poly
					(pts
						(arc
							(start -0.3302 0.4318)
							(mid -0.402042 0.402042)
							(end -0.4318 0.3302)
						)
						(arc
							(start -0.4318 -0.3302)
							(mid -0.402042 -0.402042)
							(end -0.3302 -0.4318)
						)
						(arc
							(start 0.3302 -0.4318)
							(mid 0.402042 -0.402042)
							(end 0.4318 -0.3302)
						)
						(arc
							(start 0.4318 0.3302)
							(mid 0.402042 0.402042)
							(end 0.3302 0.4318)
						)
					)
					(width 0)
					(fill yes)
				)
			)
		)
		(pad "2" smd custom
			(at 0 0.762 90)
			(size 0.2159 0.2159)
			(layers "B.Cu" "B.Mask" "B.Paste")
			(net "BMC_TPM_HW_C_RST")
			(options
				(clearance outline)
				(anchor circle)
			)
			(primitives
				(gr_poly
					(pts
						(arc
							(start -0.3302 0.4318)
							(mid -0.402042 0.402042)
							(end -0.4318 0.3302)
						)
						(arc
							(start -0.4318 -0.3302)
							(mid -0.402042 -0.402042)
							(end -0.3302 -0.4318)
						)
						(arc
							(start 0.3302 -0.4318)
							(mid 0.402042 -0.402042)
							(end 0.4318 -0.3302)
						)
						(arc
							(start 0.4318 0.3302)
							(mid 0.402042 0.402042)
							(end 0.3302 0.4318)
						)
					)
					(width 0)
					(fill yes)
				)
			)
		)
	)
	(footprint ""
		(layer "B.Cu")
		(at 419.481 -73.1901 180)
		(property "Reference" "R1R5"
			(at 0 0 0)
			(layer "B.SilkS")
			(hide yes)
			(effects
				(font
					(size 1.27 1.27)
				)
				(justify mirror)
			)
		)
		(property "Value" ""
			(at 0 0 0)
			(layer "B.Fab")
			(effects
				(font
					(size 1.27 1.27)
				)
				(justify mirror)
			)
		)
		(duplicate_pad_numbers_are_jumpers no)
		(fp_poly
			(pts
				(xy 0.2794 -0.1016) (xy -0.2794 -0.1016) (xy -0.2794 0.9906) (xy 0.2794 0.9906)
			)
			(stroke
				(width 0)
				(type default)
			)
			(fill no)
			(layer "B.CrtYd")
		)
		(fp_line
			(start 0.2794 0.9906)
			(end -0.2794 0.9906)
			(stroke
				(width 0.1)
				(type default)
			)
			(layer "B.Fab")
		)
		(fp_line
			(start 0.2794 -0.1016)
			(end 0.2794 0.9906)
			(stroke
				(width 0.1)
				(type default)
			)
			(layer "B.Fab")
		)
		(fp_line
			(start -0.2794 0.9906)
			(end -0.2794 -0.1016)
			(stroke
				(width 0.1)
				(type default)
			)
			(layer "B.Fab")
		)
		(fp_line
			(start -0.2794 -0.1016)
			(end 0.2794 -0.1016)
			(stroke
				(width 0.1)
				(type default)
			)
			(layer "B.Fab")
		)
		(pad "1" smd rect
			(at 0 0)
			(size 0.508 0.508)
			(layers "B.Cu" "B.Mask" "B.Paste")
			(net "P3V3_STBY")
		)
		(pad "2" smd rect
			(at 0 0.889)
			(size 0.508 0.508)
			(layers "B.Cu" "B.Mask" "B.Paste")
			(net "FM_FAST_PROCHOT_THROTTLE_DLY_BU")
		)
		(zone
			(layer "B.Cu")
			(hatch none 0.5)
			(connect_pads
				(clearance 0)
			)
			(min_thickness 0.25)
			(keepout
				(tracks not_allowed)
				(vias allowed)
				(pads allowed)
				(copperpour not_allowed)
				(footprints allowed)
			)
			(placement
				(enabled no)
				(sheetname "")
			)
			(fill
				(thermal_gap 0.5)
				(thermal_bridge_width 0.5)
				(island_removal_mode 0)
			)
			(polygon
				(pts
					(xy 419.227 -73.8251) (xy 419.735 -73.8251) (xy 419.735 -73.4441) (xy 419.227 -73.4441)
				)
			)
		)
		(zone
			(layer "B.Cu")
			(hatch none 0.5)
			(connect_pads
				(clearance 0)
			)
			(min_thickness 0.25)
			(keepout
				(tracks allowed)
				(vias not_allowed)
				(pads allowed)
				(copperpour not_allowed)
				(footprints allowed)
			)
			(placement
				(enabled no)
				(sheetname "")
			)
			(fill
				(thermal_gap 0.5)
				(thermal_bridge_width 0.5)
				(island_removal_mode 0)
			)
			(polygon
				(pts
					(xy 419.227 -73.4441) (xy 419.735 -73.4441) (xy 419.735 -73.8251) (xy 419.227 -73.8251)
				)
			)
		)
	)
	(footprint ""
		(layer "B.Cu")
		(at 155.293568 -144.977612 90)
		(property "Reference" "C7L6"
			(at 0 0 90)
			(layer "B.SilkS")
			(hide yes)
			(effects
				(font
					(size 1.27 1.27)
				)
				(justify mirror)
			)
		)
		(property "Value" ""
			(at 0 0 90)
			(layer "B.Fab")
			(effects
				(font
					(size 1.27 1.27)
				)
				(justify mirror)
			)
		)
		(duplicate_pad_numbers_are_jumpers no)
		(fp_rect
			(start 0.4953 1.6002)
			(end -0.4953 -0.2032)
			(stroke
				(width 0)
				(type default)
			)
			(fill no)
			(layer "B.CrtYd")
		)
		(fp_line
			(start 0.4953 -0.2032)
			(end -0.4953 -0.2032)
			(stroke
				(width 0.1)
				(type default)
			)
			(layer "B.Fab")
		)
		(fp_line
			(start -0.4953 -0.2032)
			(end -0.4953 1.6002)
			(stroke
				(width 0.1)
				(type default)
			)
			(layer "B.Fab")
		)
		(fp_line
			(start 0.4953 1.6002)
			(end 0.4953 -0.2032)
			(stroke
				(width 0.1)
				(type default)
			)
			(layer "B.Fab")
		)
		(fp_line
			(start -0.4953 1.6002)
			(end 0.4953 1.6002)
			(stroke
				(width 0.1)
				(type default)
			)
			(layer "B.Fab")
		)
		(pad "1" smd rect
			(at 0 0 270)
			(size 0.762 0.889)
			(layers "B.Cu" "B.Mask" "B.Paste")
			(net "PVPP_KLM")
		)
		(pad "2" smd rect
			(at 0 1.397 270)
			(size 0.762 0.889)
			(layers "B.Cu" "B.Mask" "B.Paste")
			(net "GND")
		)
		(zone
			(layer "B.Cu")
			(hatch none 0.5)
			(connect_pads
				(clearance 0)
			)
			(min_thickness 0.25)
			(keepout
				(tracks not_allowed)
				(vias allowed)
				(pads allowed)
				(copperpour not_allowed)
				(footprints allowed)
			)
			(placement
				(enabled no)
				(sheetname "")
			)
			(fill
				(thermal_gap 0.5)
				(thermal_bridge_width 0.5)
				(island_removal_mode 0)
			)
			(polygon
				(pts
					(xy 156.246068 -145.358612) (xy 155.738068 -145.358612) (xy 155.738068 -144.596612) (xy 156.246068 -144.596612)
				)
			)
		)
	)
	(footprint ""
		(layer "B.Cu")
		(at 318.61506 -126.31674)
		(property "Reference" "R3R5"
			(at 0 0 0)
			(layer "B.SilkS")
			(hide yes)
			(effects
				(font
					(size 1.27 1.27)
				)
				(justify mirror)
			)
		)
		(property "Value" ""
			(at 0 0 0)
			(layer "B.Fab")
			(effects
				(font
					(size 1.27 1.27)
				)
				(justify mirror)
			)
		)
		(duplicate_pad_numbers_are_jumpers no)
		(fp_poly
			(pts
				(xy 0.2794 -0.1016) (xy -0.2794 -0.1016) (xy -0.2794 0.9906) (xy 0.2794 0.9906)
			)
			(stroke
				(width 0)
				(type default)
			)
			(fill no)
			(layer "B.CrtYd")
		)
		(fp_line
			(start -0.2794 -0.1016)
			(end 0.2794 -0.1016)
			(stroke
				(width 0.1)
				(type default)
			)
			(layer "B.Fab")
		)
		(fp_line
			(start -0.2794 0.9906)
			(end -0.2794 -0.1016)
			(stroke
				(width 0.1)
				(type default)
			)
			(layer "B.Fab")
		)
		(fp_line
			(start 0.2794 -0.1016)
			(end 0.2794 0.9906)
			(stroke
				(width 0.1)
				(type default)
			)
			(layer "B.Fab")
		)
		(fp_line
			(start 0.2794 0.9906)
			(end -0.2794 0.9906)
			(stroke
				(width 0.1)
				(type default)
			)
			(layer "B.Fab")
		)
		(pad "1" smd rect
			(at 0 0 180)
			(size 0.508 0.508)
			(layers "B.Cu" "B.Mask" "B.Paste")
			(net "PVPP_DEF")
		)
		(pad "2" smd rect
			(at 0 0.889 180)
			(size 0.508 0.508)
			(layers "B.Cu" "B.Mask" "B.Paste")
			(net "SMB_DDR_DEF_VPP_SCL_R")
		)
		(zone
			(layer "B.Cu")
			(hatch none 0.5)
			(connect_pads
				(clearance 0)
			)
			(min_thickness 0.25)
			(keepout
				(tracks allowed)
				(vias not_allowed)
				(pads allowed)
				(copperpour not_allowed)
				(footprints allowed)
			)
			(placement
				(enabled no)
				(sheetname "")
			)
			(fill
				(thermal_gap 0.5)
				(thermal_bridge_width 0.5)
				(island_removal_mode 0)
			)
			(polygon
				(pts
					(xy 318.86906 -126.06274) (xy 318.36106 -126.06274) (xy 318.36106 -125.68174) (xy 318.86906 -125.68174)
				)
			)
		)
		(zone
			(layer "B.Cu")
			(hatch none 0.5)
			(connect_pads
				(clearance 0)
			)
			(min_thickness 0.25)
			(keepout
				(tracks not_allowed)
				(vias allowed)
				(pads allowed)
				(copperpour not_allowed)
				(footprints allowed)
			)
			(placement
				(enabled no)
				(sheetname "")
			)
			(fill
				(thermal_gap 0.5)
				(thermal_bridge_width 0.5)
				(island_removal_mode 0)
			)
			(polygon
				(pts
					(xy 318.86906 -125.68174) (xy 318.36106 -125.68174) (xy 318.36106 -126.06274) (xy 318.86906 -126.06274)
				)
			)
		)
	)
	(footprint ""
		(layer "B.Cu")
		(at 337.1596 -85.70722)
		(property "Reference" "R3P54"
			(at 0 0 0)
			(layer "B.SilkS")
			(hide yes)
			(effects
				(font
					(size 1.27 1.27)
				)
				(justify mirror)
			)
		)
		(property "Value" ""
			(at 0 0 0)
			(layer "B.Fab")
			(effects
				(font
					(size 1.27 1.27)
				)
				(justify mirror)
			)
		)
		(duplicate_pad_numbers_are_jumpers no)
		(fp_poly
			(pts
				(xy 0.2794 -0.1016) (xy -0.2794 -0.1016) (xy -0.2794 0.9906) (xy 0.2794 0.9906)
			)
			(stroke
				(width 0)
				(type default)
			)
			(fill no)
			(layer "B.CrtYd")
		)
		(fp_line
			(start -0.2794 -0.1016)
			(end 0.2794 -0.1016)
			(stroke
				(width 0.1)
				(type default)
			)
			(layer "B.Fab")
		)
		(fp_line
			(start -0.2794 0.9906)
			(end -0.2794 -0.1016)
			(stroke
				(width 0.1)
				(type default)
			)
			(layer "B.Fab")
		)
		(fp_line
			(start 0.2794 -0.1016)
			(end 0.2794 0.9906)
			(stroke
				(width 0.1)
				(type default)
			)
			(layer "B.Fab")
		)
		(fp_line
			(start 0.2794 0.9906)
			(end -0.2794 0.9906)
			(stroke
				(width 0.1)
				(type default)
			)
			(layer "B.Fab")
		)
		(pad "1" smd rect
			(at 0 0 180)
			(size 0.508 0.508)
			(layers "B.Cu" "B.Mask" "B.Paste")
			(net "P3V3_STBY")
		)
		(pad "2" smd rect
			(at 0 0.889 180)
			(size 0.508 0.508)
			(layers "B.Cu" "B.Mask" "B.Paste")
			(net "FM_CPU0_SM_WP")
		)
		(zone
			(layer "B.Cu")
			(hatch none 0.5)
			(connect_pads
				(clearance 0)
			)
			(min_thickness 0.25)
			(keepout
				(tracks allowed)
				(vias not_allowed)
				(pads allowed)
				(copperpour not_allowed)
				(footprints allowed)
			)
			(placement
				(enabled no)
				(sheetname "")
			)
			(fill
				(thermal_gap 0.5)
				(thermal_bridge_width 0.5)
				(island_removal_mode 0)
			)
			(polygon
				(pts
					(xy 337.4136 -85.45322) (xy 336.9056 -85.45322) (xy 336.9056 -85.07222) (xy 337.4136 -85.07222)
				)
			)
		)
		(zone
			(layer "B.Cu")
			(hatch none 0.5)
			(connect_pads
				(clearance 0)
			)
			(min_thickness 0.25)
			(keepout
				(tracks not_allowed)
				(vias allowed)
				(pads allowed)
				(copperpour not_allowed)
				(footprints allowed)
			)
			(placement
				(enabled no)
				(sheetname "")
			)
			(fill
				(thermal_gap 0.5)
				(thermal_bridge_width 0.5)
				(island_removal_mode 0)
			)
			(polygon
				(pts
					(xy 337.4136 -85.07222) (xy 336.9056 -85.07222) (xy 336.9056 -85.45322) (xy 337.4136 -85.45322)
				)
			)
		)
	)
)
